(kicad_pcb
	(version 20260206)
	(generator "pcbnew")
	(generator_version "10.0")
	(general
		(thickness 1.6)
		(legacy_teardrops no)
	)
	(paper "A4")
	(title_block
		(title "Wiwynn_Tioga_Pass_MB.brd")
		(comment 1 "Tioga Pass / footprints 3231-3238 of 4770")
	)
	(layers
		(0 "F.Cu" signal "TOP")
		(4 "In1.Cu" signal "L2GND")
		(6 "In2.Cu" signal "L3")
		(8 "In3.Cu" signal "L4GND")
		(10 "In4.Cu" signal "L5")
		(12 "In5.Cu" signal "L6GND")
		(14 "In6.Cu" signal "L7VCC")
		(16 "In7.Cu" signal "L8VCC")
		(18 "In8.Cu" signal "L9GND")
		(20 "In9.Cu" signal "L10")
		(22 "In10.Cu" signal "L11GND")
		(24 "In11.Cu" signal "L12")
		(26 "In12.Cu" signal "L13GND")
		(2 "B.Cu" signal "BOTTOM")
		(9 "F.Adhes" user "F.Adhesive")
		(11 "B.Adhes" user "B.Adhesive")
		(13 "F.Paste" user "Package Geometry/Pastemask Top")
		(15 "B.Paste" user "Package Geometry/Pastemask Bottom")
		(5 "F.SilkS" user "Ref Des/Silkscreen Top")
		(7 "B.SilkS" user "Ref Des/Silkscreen Bottom")
		(1 "F.Mask" user "Board Geometry/Soldermask Top")
		(3 "B.Mask" user "Board Geometry/Soldermask Bottom")
		(17 "Dwgs.User" user "User.Drawings")
		(19 "Cmts.User" user "User.Comments")
		(21 "Eco1.User" user "User.Eco1")
		(23 "Eco2.User" user "User.Eco2")
		(25 "Edge.Cuts" user "Board Geometry/Outline")
		(27 "Margin" user)
		(31 "F.CrtYd" user "Package Geometry/Place Bound Top")
		(29 "B.CrtYd" user "Package Geometry/Place Bound Bottom")
		(35 "F.Fab" user "Ref Des/Assembly Top")
		(33 "B.Fab" user "Ref Des/Assembly Bottom")
	)
	(footprint ""
		(layer "B.Cu")
		(at 93.241368 -17.6276 -90)
		(property "Reference" "C8T11"
			(at 0 0 90)
			(layer "B.SilkS")
			(hide yes)
			(effects
				(font
					(size 1.27 1.27)
				)
				(justify mirror)
			)
		)
		(property "Value" ""
			(at 0 0 90)
			(layer "B.Fab")
			(effects
				(font
					(size 1.27 1.27)
				)
				(justify mirror)
			)
		)
		(duplicate_pad_numbers_are_jumpers no)
		(fp_rect
			(start 0.500126 1.598422)
			(end -0.500126 -0.201422)
			(stroke
				(width 0)
				(type default)
			)
			(fill no)
			(layer "B.CrtYd")
		)
		(fp_line
			(start -0.500126 1.598422)
			(end 0.500126 1.598422)
			(stroke
				(width 0.1)
				(type default)
			)
			(layer "B.Fab")
		)
		(fp_line
			(start 0.500126 1.598422)
			(end 0.500126 -0.201422)
			(stroke
				(width 0.1)
				(type default)
			)
			(layer "B.Fab")
		)
		(fp_line
			(start -0.500126 -0.201422)
			(end -0.500126 1.598422)
			(stroke
				(width 0.1)
				(type default)
			)
			(layer "B.Fab")
		)
		(fp_line
			(start 0.500126 -0.201422)
			(end -0.500126 -0.201422)
			(stroke
				(width 0.1)
				(type default)
			)
			(layer "B.Fab")
		)
		(pad "1" smd rect
			(at 0 0 180)
			(size 0.889 0.9906)
			(layers "B.Cu" "B.Mask" "B.Paste")
			(net "PVDDQ_GHJ")
		)
		(pad "2" smd rect
			(at 0 1.397 180)
			(size 0.889 0.9906)
			(layers "B.Cu" "B.Mask" "B.Paste")
			(net "GND")
		)
		(zone
			(layer "B.Cu")
			(hatch none 0.5)
			(connect_pads
				(clearance 0)
			)
			(min_thickness 0.25)
			(keepout
				(tracks allowed)
				(vias not_allowed)
				(pads allowed)
				(copperpour not_allowed)
				(footprints allowed)
			)
			(placement
				(enabled no)
				(sheetname "")
			)
			(fill
				(thermal_gap 0.5)
				(thermal_bridge_width 0.5)
				(island_removal_mode 0)
			)
			(polygon
				(pts
					(xy 92.288868 -17.1323) (xy 92.796868 -17.1323) (xy 92.796868 -18.1229) (xy 92.288868 -18.1229)
				)
			)
		)
		(zone
			(layer "B.Cu")
			(hatch none 0.5)
			(connect_pads
				(clearance 0)
			)
			(min_thickness 0.25)
			(keepout
				(tracks not_allowed)
				(vias allowed)
				(pads allowed)
				(copperpour not_allowed)
				(footprints allowed)
			)
			(placement
				(enabled no)
				(sheetname "")
			)
			(fill
				(thermal_gap 0.5)
				(thermal_bridge_width 0.5)
				(island_removal_mode 0)
			)
			(polygon
				(pts
					(xy 92.288868 -17.1323) (xy 92.796868 -17.1323) (xy 92.796868 -18.1229) (xy 92.288868 -18.1229)
				)
			)
		)
	)
	(footprint ""
		(layer "B.Cu")
		(at 489.65739 -146.177 90)
		(property "Reference" "R1L18"
			(at 0 0 90)
			(layer "B.SilkS")
			(hide yes)
			(effects
				(font
					(size 1.27 1.27)
				)
				(justify mirror)
			)
		)
		(property "Value" ""
			(at 0 0 90)
			(layer "B.Fab")
			(effects
				(font
					(size 1.27 1.27)
				)
				(justify mirror)
			)
		)
		(duplicate_pad_numbers_are_jumpers no)
		(fp_poly
			(pts
				(xy 0.2794 -0.1016) (xy -0.2794 -0.1016) (xy -0.2794 0.9906) (xy 0.2794 0.9906)
			)
			(stroke
				(width 0)
				(type default)
			)
			(fill no)
			(layer "B.CrtYd")
		)
		(fp_line
			(start 0.2794 -0.1016)
			(end 0.2794 0.9906)
			(stroke
				(width 0.1)
				(type default)
			)
			(layer "B.Fab")
		)
		(fp_line
			(start -0.2794 -0.1016)
			(end 0.2794 -0.1016)
			(stroke
				(width 0.1)
				(type default)
			)
			(layer "B.Fab")
		)
		(fp_line
			(start 0.2794 0.9906)
			(end -0.2794 0.9906)
			(stroke
				(width 0.1)
				(type default)
			)
			(layer "B.Fab")
		)
		(fp_line
			(start -0.2794 0.9906)
			(end -0.2794 -0.1016)
			(stroke
				(width 0.1)
				(type default)
			)
			(layer "B.Fab")
		)
		(pad "1" smd rect
			(at 0 0 270)
			(size 0.508 0.508)
			(layers "B.Cu" "B.Mask" "B.Paste")
			(net "LED_POSTCODE_5")
		)
		(pad "2" smd rect
			(at 0 0.889 270)
			(size 0.508 0.508)
			(layers "B.Cu" "B.Mask" "B.Paste")
			(net "LED_POSTCODE_5_R")
		)
		(zone
			(layer "B.Cu")
			(hatch none 0.5)
			(connect_pads
				(clearance 0)
			)
			(min_thickness 0.25)
			(keepout
				(tracks allowed)
				(vias not_allowed)
				(pads allowed)
				(copperpour not_allowed)
				(footprints allowed)
			)
			(placement
				(enabled no)
				(sheetname "")
			)
			(fill
				(thermal_gap 0.5)
				(thermal_bridge_width 0.5)
				(island_removal_mode 0)
			)
			(polygon
				(pts
					(xy 489.91139 -146.431) (xy 489.91139 -145.923) (xy 490.29239 -145.923) (xy 490.29239 -146.431)
				)
			)
		)
		(zone
			(layer "B.Cu")
			(hatch none 0.5)
			(connect_pads
				(clearance 0)
			)
			(min_thickness 0.25)
			(keepout
				(tracks not_allowed)
				(vias allowed)
				(pads allowed)
				(copperpour not_allowed)
				(footprints allowed)
			)
			(placement
				(enabled no)
				(sheetname "")
			)
			(fill
				(thermal_gap 0.5)
				(thermal_bridge_width 0.5)
				(island_removal_mode 0)
			)
			(polygon
				(pts
					(xy 490.29239 -146.431) (xy 490.29239 -145.923) (xy 489.91139 -145.923) (xy 489.91139 -146.431)
				)
			)
		)
	)
	(footprint ""
		(layer "B.Cu")
		(at 381.7239 -84.6836 180)
		(property "Reference" "R3N30"
			(at 0.8382 -0.67818 180)
			(unlocked yes)
			(layer "B.SilkS")
			(effects
				(font
					(size 0.4064 0.254)
					(thickness 0.1524)
				)
				(justify left mirror)
			)
		)
		(property "Value" ""
			(at 0 0 0)
			(layer "B.Fab")
			(effects
				(font
					(size 1.27 1.27)
				)
				(justify mirror)
			)
		)
		(duplicate_pad_numbers_are_jumpers no)
		(fp_poly
			(pts
				(xy 0.2794 -0.1016) (xy -0.2794 -0.1016) (xy -0.2794 0.9906) (xy 0.2794 0.9906)
			)
			(stroke
				(width 0)
				(type default)
			)
			(fill no)
			(layer "B.CrtYd")
		)
		(fp_line
			(start 0.2794 0.9906)
			(end -0.2794 0.9906)
			(stroke
				(width 0.1)
				(type default)
			)
			(layer "B.Fab")
		)
		(fp_line
			(start 0.2794 -0.1016)
			(end 0.2794 0.9906)
			(stroke
				(width 0.1)
				(type default)
			)
			(layer "B.Fab")
		)
		(fp_line
			(start -0.2794 0.9906)
			(end -0.2794 -0.1016)
			(stroke
				(width 0.1)
				(type default)
			)
			(layer "B.Fab")
		)
		(fp_line
			(start -0.2794 -0.1016)
			(end 0.2794 -0.1016)
			(stroke
				(width 0.1)
				(type default)
			)
			(layer "B.Fab")
		)
		(pad "1" smd rect
			(at 0 0)
			(size 0.508 0.508)
			(layers "B.Cu" "B.Mask" "B.Paste")
			(net "H_CPU0_MEMABC_MEMHOT_LVT3_N")
		)
		(pad "2" smd rect
			(at 0 0.889)
			(size 0.508 0.508)
			(layers "B.Cu" "B.Mask" "B.Paste")
			(net "H_CPU0_MEMABC_MEMHOT_PCH_N")
		)
		(zone
			(layer "B.Cu")
			(hatch none 0.5)
			(connect_pads
				(clearance 0)
			)
			(min_thickness 0.25)
			(keepout
				(tracks not_allowed)
				(vias allowed)
				(pads allowed)
				(copperpour not_allowed)
				(footprints allowed)
			)
			(placement
				(enabled no)
				(sheetname "")
			)
			(fill
				(thermal_gap 0.5)
				(thermal_bridge_width 0.5)
				(island_removal_mode 0)
			)
			(polygon
				(pts
					(xy 381.4699 -85.3186) (xy 381.9779 -85.3186) (xy 381.9779 -84.9376) (xy 381.4699 -84.9376)
				)
			)
		)
		(zone
			(layer "B.Cu")
			(hatch none 0.5)
			(connect_pads
				(clearance 0)
			)
			(min_thickness 0.25)
			(keepout
				(tracks allowed)
				(vias not_allowed)
				(pads allowed)
				(copperpour not_allowed)
				(footprints allowed)
			)
			(placement
				(enabled no)
				(sheetname "")
			)
			(fill
				(thermal_gap 0.5)
				(thermal_bridge_width 0.5)
				(island_removal_mode 0)
			)
			(polygon
				(pts
					(xy 381.4699 -84.9376) (xy 381.9779 -84.9376) (xy 381.9779 -85.3186) (xy 381.4699 -85.3186)
				)
			)
		)
	)
	(footprint ""
		(layer "B.Cu")
		(at 403.391624 -32.801052)
		(property "Reference" "C25W35"
			(at 0.8382 -0.67818 0)
			(unlocked yes)
			(layer "B.SilkS")
			(effects
				(font
					(size 0.4064 0.254)
					(thickness 0.1524)
				)
				(justify left mirror)
			)
		)
		(property "Value" ""
			(at 0 0 0)
			(layer "B.Fab")
			(effects
				(font
					(size 1.27 1.27)
				)
				(justify mirror)
			)
		)
		(duplicate_pad_numbers_are_jumpers no)
		(fp_poly
			(pts
				(xy -0.3048 -0.1016) (xy -0.3048 0.9906) (xy 0.3048 0.9906) (xy 0.3048 -0.1016)
			)
			(stroke
				(width 0)
				(type default)
			)
			(fill no)
			(layer "B.CrtYd")
		)
		(fp_line
			(start -0.3048 -0.1016)
			(end 0.3048 -0.1016)
			(stroke
				(width 0.1)
				(type default)
			)
			(layer "B.Fab")
		)
		(fp_line
			(start -0.3048 0.9906)
			(end -0.3048 -0.1016)
			(stroke
				(width 0.1)
				(type default)
			)
			(layer "B.Fab")
		)
		(fp_line
			(start 0.3048 -0.1016)
			(end 0.3048 0.9906)
			(stroke
				(width 0.1)
				(type default)
			)
			(layer "B.Fab")
		)
		(fp_line
			(start 0.3048 0.9906)
			(end -0.3048 0.9906)
			(stroke
				(width 0.1)
				(type default)
			)
			(layer "B.Fab")
		)
		(pad "1" smd rect
			(at 0 0 180)
			(size 0.508 0.508)
			(layers "B.Cu" "B.Mask" "B.Paste")
			(net "VCC_DACAV3V3")
		)
		(pad "2" smd rect
			(at 0 0.889 180)
			(size 0.508 0.508)
			(layers "B.Cu" "B.Mask" "B.Paste")
			(net "GND")
		)
		(zone
			(layer "B.Cu")
			(hatch none 0.5)
			(connect_pads
				(clearance 0)
			)
			(min_thickness 0.25)
			(keepout
				(tracks allowed)
				(vias not_allowed)
				(pads allowed)
				(copperpour not_allowed)
				(footprints allowed)
			)
			(placement
				(enabled no)
				(sheetname "")
			)
			(fill
				(thermal_gap 0.5)
				(thermal_bridge_width 0.5)
				(island_removal_mode 0)
			)
			(polygon
				(pts
					(xy 403.645624 -32.547052) (xy 403.137624 -32.547052) (xy 403.137624 -32.166052) (xy 403.645624 -32.166052)
				)
			)
		)
		(zone
			(layer "B.Cu")
			(hatch none 0.5)
			(connect_pads
				(clearance 0)
			)
			(min_thickness 0.25)
			(keepout
				(tracks not_allowed)
				(vias allowed)
				(pads allowed)
				(copperpour not_allowed)
				(footprints allowed)
			)
			(placement
				(enabled no)
				(sheetname "")
			)
			(fill
				(thermal_gap 0.5)
				(thermal_bridge_width 0.5)
				(island_removal_mode 0)
			)
			(polygon
				(pts
					(xy 403.645624 -32.166052) (xy 403.137624 -32.166052) (xy 403.137624 -32.547052) (xy 403.645624 -32.547052)
				)
			)
		)
	)
	(footprint ""
		(layer "B.Cu")
		(at 280.735024 -80.096614 180)
		(property "Reference" "C4P1"
			(at 0 0 0)
			(layer "B.SilkS")
			(hide yes)
			(effects
				(font
					(size 1.27 1.27)
				)
				(justify mirror)
			)
		)
		(property "Value" ""
			(at 0 0 0)
			(layer "B.Fab")
			(effects
				(font
					(size 1.27 1.27)
				)
				(justify mirror)
			)
		)
		(duplicate_pad_numbers_are_jumpers no)
		(fp_poly
			(pts
				(xy 0.7239 -0.2159) (xy -0.7239 -0.2159) (xy -0.7239 1.9939) (xy 0.7239 1.9939)
			)
			(stroke
				(width 0)
				(type default)
			)
			(fill no)
			(layer "B.CrtYd")
		)
		(fp_line
			(start 0.7239 1.9939)
			(end -0.7239 1.9939)
			(stroke
				(width 0.1)
				(type default)
			)
			(layer "B.Fab")
		)
		(fp_line
			(start 0.7239 -0.2159)
			(end 0.7239 1.9939)
			(stroke
				(width 0.1)
				(type default)
			)
			(layer "B.Fab")
		)
		(fp_line
			(start -0.7239 1.9939)
			(end -0.7239 -0.2159)
			(stroke
				(width 0.1)
				(type default)
			)
			(layer "B.Fab")
		)
		(fp_line
			(start -0.7239 -0.2159)
			(end 0.7239 -0.2159)
			(stroke
				(width 0.1)
				(type default)
			)
			(layer "B.Fab")
		)
		(pad "1" smd rect
			(at 0 0)
			(size 1.27 1.016)
			(layers "B.Cu" "B.Mask" "B.Paste")
			(net "PVCCIO_CPU0")
		)
		(pad "2" smd rect
			(at 0 1.778)
			(size 1.27 1.016)
			(layers "B.Cu" "B.Mask" "B.Paste")
			(net "GND")
		)
		(zone
			(layer "B.Cu")
			(hatch none 0.5)
			(connect_pads
				(clearance 0)
			)
			(min_thickness 0.25)
			(keepout
				(tracks not_allowed)
				(vias allowed)
				(pads allowed)
				(copperpour not_allowed)
				(footprints allowed)
			)
			(placement
				(enabled no)
				(sheetname "")
			)
			(fill
				(thermal_gap 0.5)
				(thermal_bridge_width 0.5)
				(island_removal_mode 0)
			)
			(polygon
				(pts
					(xy 280.100024 -80.604614) (xy 281.370024 -80.604614) (xy 281.370024 -81.366614) (xy 280.100024 -81.366614)
				)
			)
		)
	)
	(footprint ""
		(layer "B.Cu")
		(at 456.7555 -135.0772 180)
		(property "Reference" "C1L19"
			(at 0 0 0)
			(layer "B.SilkS")
			(hide yes)
			(effects
				(font
					(size 1.27 1.27)
				)
				(justify mirror)
			)
		)
		(property "Value" ""
			(at 0 0 0)
			(layer "B.Fab")
			(effects
				(font
					(size 1.27 1.27)
				)
				(justify mirror)
			)
		)
		(duplicate_pad_numbers_are_jumpers no)
		(fp_poly
			(pts
				(xy -0.3048 -0.1016) (xy -0.3048 0.9906) (xy 0.3048 0.9906) (xy 0.3048 -0.1016)
			)
			(stroke
				(width 0)
				(type default)
			)
			(fill no)
			(layer "B.CrtYd")
		)
		(fp_line
			(start 0.3048 0.9906)
			(end -0.3048 0.9906)
			(stroke
				(width 0.1)
				(type default)
			)
			(layer "B.Fab")
		)
		(fp_line
			(start 0.3048 -0.1016)
			(end 0.3048 0.9906)
			(stroke
				(width 0.1)
				(type default)
			)
			(layer "B.Fab")
		)
		(fp_line
			(start -0.3048 0.9906)
			(end -0.3048 -0.1016)
			(stroke
				(width 0.1)
				(type default)
			)
			(layer "B.Fab")
		)
		(fp_line
			(start -0.3048 -0.1016)
			(end 0.3048 -0.1016)
			(stroke
				(width 0.1)
				(type default)
			)
			(layer "B.Fab")
		)
		(pad "1" smd rect
			(at 0 0)
			(size 0.508 0.508)
			(layers "B.Cu" "B.Mask" "B.Paste")
			(net "P3V3_STBY")
		)
		(pad "2" smd rect
			(at 0 0.889)
			(size 0.508 0.508)
			(layers "B.Cu" "B.Mask" "B.Paste")
			(net "GND")
		)
		(zone
			(layer "B.Cu")
			(hatch none 0.5)
			(connect_pads
				(clearance 0)
			)
			(min_thickness 0.25)
			(keepout
				(tracks not_allowed)
				(vias allowed)
				(pads allowed)
				(copperpour not_allowed)
				(footprints allowed)
			)
			(placement
				(enabled no)
				(sheetname "")
			)
			(fill
				(thermal_gap 0.5)
				(thermal_bridge_width 0.5)
				(island_removal_mode 0)
			)
			(polygon
				(pts
					(xy 456.5015 -135.7122) (xy 457.0095 -135.7122) (xy 457.0095 -135.3312) (xy 456.5015 -135.3312)
				)
			)
		)
		(zone
			(layer "B.Cu")
			(hatch none 0.5)
			(connect_pads
				(clearance 0)
			)
			(min_thickness 0.25)
			(keepout
				(tracks allowed)
				(vias not_allowed)
				(pads allowed)
				(copperpour not_allowed)
				(footprints allowed)
			)
			(placement
				(enabled no)
				(sheetname "")
			)
			(fill
				(thermal_gap 0.5)
				(thermal_bridge_width 0.5)
				(island_removal_mode 0)
			)
			(polygon
				(pts
					(xy 456.5015 -135.3312) (xy 457.0095 -135.3312) (xy 457.0095 -135.7122) (xy 456.5015 -135.7122)
				)
			)
		)
	)
	(footprint ""
		(layer "B.Cu")
		(at 330.581 -5.969)
		(property "Reference" "R4U4"
			(at 0 0 0)
			(layer "B.SilkS")
			(hide yes)
			(effects
				(font
					(size 1.27 1.27)
				)
				(justify mirror)
			)
		)
		(property "Value" ""
			(at 0 0 0)
			(layer "B.Fab")
			(effects
				(font
					(size 1.27 1.27)
				)
				(justify mirror)
			)
		)
		(duplicate_pad_numbers_are_jumpers no)
		(fp_poly
			(pts
				(xy 0.2794 -0.1016) (xy -0.2794 -0.1016) (xy -0.2794 0.9906) (xy 0.2794 0.9906)
			)
			(stroke
				(width 0)
				(type default)
			)
			(fill no)
			(layer "B.CrtYd")
		)
		(fp_line
			(start -0.2794 -0.1016)
			(end 0.2794 -0.1016)
			(stroke
				(width 0.1)
				(type default)
			)
			(layer "B.Fab")
		)
		(fp_line
			(start -0.2794 0.9906)
			(end -0.2794 -0.1016)
			(stroke
				(width 0.1)
				(type default)
			)
			(layer "B.Fab")
		)
		(fp_line
			(start 0.2794 -0.1016)
			(end 0.2794 0.9906)
			(stroke
				(width 0.1)
				(type default)
			)
			(layer "B.Fab")
		)
		(fp_line
			(start 0.2794 0.9906)
			(end -0.2794 0.9906)
			(stroke
				(width 0.1)
				(type default)
			)
			(layer "B.Fab")
		)
		(pad "1" smd rect
			(at 0 0 180)
			(size 0.508 0.508)
			(layers "B.Cu" "B.Mask" "B.Paste")
			(net "FM_DIMM_EVENT_FET")
		)
		(pad "2" smd rect
			(at 0 0.889 180)
			(size 0.508 0.508)
			(layers "B.Cu" "B.Mask" "B.Paste")
			(net "GND")
		)
		(zone
			(layer "B.Cu")
			(hatch none 0.5)
			(connect_pads
				(clearance 0)
			)
			(min_thickness 0.25)
			(keepout
				(tracks allowed)
				(vias not_allowed)
				(pads allowed)
				(copperpour not_allowed)
				(footprints allowed)
			)
			(placement
				(enabled no)
				(sheetname "")
			)
			(fill
				(thermal_gap 0.5)
				(thermal_bridge_width 0.5)
				(island_removal_mode 0)
			)
			(polygon
				(pts
					(xy 330.835 -5.715) (xy 330.327 -5.715) (xy 330.327 -5.334) (xy 330.835 -5.334)
				)
			)
		)
		(zone
			(layer "B.Cu")
			(hatch none 0.5)
			(connect_pads
				(clearance 0)
			)
			(min_thickness 0.25)
			(keepout
				(tracks not_allowed)
				(vias allowed)
				(pads allowed)
				(copperpour not_allowed)
				(footprints allowed)
			)
			(placement
				(enabled no)
				(sheetname "")
			)
			(fill
				(thermal_gap 0.5)
				(thermal_bridge_width 0.5)
				(island_removal_mode 0)
			)
			(polygon
				(pts
					(xy 330.835 -5.334) (xy 330.327 -5.334) (xy 330.327 -5.715) (xy 330.835 -5.715)
				)
			)
		)
	)
	(footprint ""
		(layer "B.Cu")
		(at 183.795416 -59.238896 180)
		(property "Reference" "C22W14"
			(at 0 0 0)
			(layer "B.SilkS")
			(hide yes)
			(effects
				(font
					(size 1.27 1.27)
				)
				(justify mirror)
			)
		)
		(property "Value" "*"
			(at 0.0762 -6.2357 180)
			(unlocked yes)
			(layer "B.Fab")
			(hide yes)
			(effects
				(font
					(size 1.27 1.016)
					(thickness 0.1524)
				)
				(justify mirror)
			)
		)
		(property "Device Type" "SC22U16V5MX-4-GP_SMD-BCG5-SC22A"
			(at 0.0762 -8.2677 180)
			(unlocked yes)
			(layer "B.Fab")
			(hide yes)
			(effects
				(font
					(size 1.27 1.016)
					(thickness 0.1524)
				)
				(justify mirror)
			)
		)
		(duplicate_pad_numbers_are_jumpers no)
		(fp_line
			(start -0.635 0)
			(end 0.635 0)
			(stroke
				(width 0.508)
				(type default)
			)
			(layer "B.SilkS")
		)
		(fp_rect
			(start 0.9652 1.778)
			(end -0.9652 -1.778)
			(stroke
				(width 0)
				(type default)
			)
			(fill no)
			(layer "B.CrtYd")
		)
		(fp_poly
			(pts
				(xy 0.9652 -1.778) (xy -0.9652 -1.778) (xy -0.9652 1.778) (xy 0.9652 1.778)
			)
			(stroke
				(width 0)
				(type default)
			)
			(fill no)
			(layer "B.Fab")
		)
		(pad "1" smd rect
			(at 0 -0.9652)
			(size 1.397 1.143)
			(layers "B.Cu" "B.Mask" "B.Paste")
			(net "VR_FET_SW_P12V_STBY_PVCCIN_CPU0")
		)
		(pad "2" smd rect
			(at 0 0.9652)
			(size 1.397 1.143)
			(layers "B.Cu" "B.Mask" "B.Paste")
			(net "GND")
		)
	)
)
